(kicad_pcb
	(version 20260206)
	(generator "pcbnew")
	(generator_version "10.0")
	(general
		(thickness 1.6)
		(legacy_teardrops no)
	)
	(paper "A4")
	(title_block
		(title "01162023_DA0F0TEBIF0_F0T_Expander_BD_F_brd_V02_OCP.brd")
		(comment 1 "Grand Teton / footprints 114-115 of 9728")
	)
	(layers
		(0 "F.Cu" signal "TOP")
		(4 "In1.Cu" signal "GND")
		(6 "In2.Cu" signal "VCC")
		(8 "In3.Cu" signal "VCC1")
		(10 "In4.Cu" signal "GND1")
		(12 "In5.Cu" signal "IN1")
		(14 "In6.Cu" signal "GND2")
		(16 "In7.Cu" signal "IN2")
		(18 "In8.Cu" signal "GND3")
		(20 "In9.Cu" signal "IN3")
		(22 "In10.Cu" signal "GND4")
		(24 "In11.Cu" signal "IN4")
		(26 "In12.Cu" signal "GND5")
		(28 "In13.Cu" signal "IN5")
		(30 "In14.Cu" signal "GND6")
		(32 "In15.Cu" signal "IN6")
		(34 "In16.Cu" signal "GND7")
		(2 "B.Cu" signal "BOTTOM")
		(9 "F.Adhes" user "F.Adhesive")
		(11 "B.Adhes" user "B.Adhesive")
		(13 "F.Paste" user "Package Geometry/Pastemask Top")
		(15 "B.Paste" user "Package Geometry/Pastemask Bottom")
		(5 "F.SilkS" user "Ref Des/Silkscreen Top")
		(7 "B.SilkS" user "Ref Des/Silkscreen Bottom")
		(1 "F.Mask" user "Board Geometry/Soldermask Top")
		(3 "B.Mask" user "Board Geometry/Soldermask Bottom")
		(17 "Dwgs.User" user "User.Drawings")
		(19 "Cmts.User" user "User.Comments")
		(21 "Eco1.User" user "User.Eco1")
		(23 "Eco2.User" user "User.Eco2")
		(25 "Edge.Cuts" user "Board Geometry/Outline")
		(27 "Margin" user)
		(31 "F.CrtYd" user "Package Geometry/Place Bound Top")
		(29 "B.CrtYd" user "Package Geometry/Place Bound Bottom")
		(35 "F.Fab" user "Ref Des/Assembly Top")
		(33 "B.Fab" user "Ref Des/Assembly Bottom")
	)
	(footprint ""
		(layer "F.Cu")
		(at 120.77573 -258.394962 90)
		(property "Reference" "PU6"
			(at -6.600952 0.403098 0)
			(unlocked yes)
			(layer "F.SilkS")
			(effects
				(font
					(size 0.7874 0.5842)
					(thickness 0.1524)
				)
				(justify left)
			)
		)
		(property "Value" ""
			(at 0 0 90)
			(layer "F.Fab")
			(effects
				(font
					(size 1.27 1.27)
				)
			)
		)
		(duplicate_pad_numbers_are_jumpers no)
		(fp_line
			(start 0.1778 -3.2385)
			(end 0.1778 -2.8575)
			(stroke
				(width 0.1524)
				(type default)
			)
			(layer "F.SilkS")
		)
		(fp_line
			(start -1.8034 -2.8702)
			(end -1.8034 -3.6322)
			(stroke
				(width 0.1524)
				(type default)
			)
			(layer "F.SilkS")
		)
		(fp_line
			(start 2.500122 -2.500122)
			(end 2.500122 -2.015998)
			(stroke
				(width 0.1524)
				(type default)
			)
			(layer "F.SilkS")
		)
		(fp_line
			(start 2.015998 -2.500122)
			(end 2.500122 -2.500122)
			(stroke
				(width 0.1524)
				(type default)
			)
			(layer "F.SilkS")
		)
		(fp_line
			(start -2.500122 -2.500122)
			(end -2.015998 -2.500122)
			(stroke
				(width 0.1524)
				(type default)
			)
			(layer "F.SilkS")
		)
		(fp_line
			(start -2.500122 -2.015998)
			(end -2.500122 -2.500122)
			(stroke
				(width 0.1524)
				(type default)
			)
			(layer "F.SilkS")
		)
		(fp_line
			(start 2.8702 -1.778)
			(end 3.6322 -1.778)
			(stroke
				(width 0.1524)
				(type default)
			)
			(layer "F.SilkS")
		)
		(fp_line
			(start -3.2639 -0.1778)
			(end -2.8829 -0.1778)
			(stroke
				(width 0.1524)
				(type default)
			)
			(layer "F.SilkS")
		)
		(fp_line
			(start 2.8829 0.2032)
			(end 3.2639 0.2032)
			(stroke
				(width 0.1524)
				(type default)
			)
			(layer "F.SilkS")
		)
		(fp_line
			(start -3.6576 1.8034)
			(end -2.8956 1.8034)
			(stroke
				(width 0.1524)
				(type default)
			)
			(layer "F.SilkS")
		)
		(fp_line
			(start 2.500122 2.015998)
			(end 2.500122 2.500122)
			(stroke
				(width 0.1524)
				(type default)
			)
			(layer "F.SilkS")
		)
		(fp_line
			(start 2.500122 2.500122)
			(end 2.015998 2.500122)
			(stroke
				(width 0.1524)
				(type default)
			)
			(layer "F.SilkS")
		)
		(fp_line
			(start -2.015998 2.500122)
			(end -2.500122 2.500122)
			(stroke
				(width 0.1524)
				(type default)
			)
			(layer "F.SilkS")
		)
		(fp_line
			(start -2.500122 2.500122)
			(end -2.500122 2.018538)
			(stroke
				(width 0.1524)
				(type default)
			)
			(layer "F.SilkS")
		)
		(fp_line
			(start -0.2032 2.8829)
			(end -0.2032 3.2639)
			(stroke
				(width 0.1524)
				(type default)
			)
			(layer "F.SilkS")
		)
		(fp_line
			(start 1.778 3.6322)
			(end 1.778 2.8702)
			(stroke
				(width 0.1524)
				(type default)
			)
			(layer "F.SilkS")
		)
		(fp_poly
			(pts
				(xy -2.921 -1.800098) (xy -3.504184 -1.508506) (xy -3.504184 -2.09169)
			)
			(stroke
				(width 0)
				(type default)
			)
			(fill yes)
			(layer "F.SilkS")
		)
		(fp_line
			(start 0.1778 -3.2385)
			(end 0.1778 -2.8575)
			(stroke
				(width 0.1)
				(type default)
			)
			(layer "F.Fab")
		)
		(fp_line
			(start -1.8034 -2.8702)
			(end -1.8034 -3.6322)
			(stroke
				(width 0.1)
				(type default)
			)
			(layer "F.Fab")
		)
		(fp_line
			(start 2.500122 -2.500122)
			(end 2.500122 2.500122)
			(stroke
				(width 0.1)
				(type default)
			)
			(layer "F.Fab")
		)
		(fp_line
			(start -2.500122 -2.500122)
			(end 2.500122 -2.500122)
			(stroke
				(width 0.1)
				(type default)
			)
			(layer "F.Fab")
		)
		(fp_line
			(start 2.8702 -1.778)
			(end 3.6322 -1.778)
			(stroke
				(width 0.1)
				(type default)
			)
			(layer "F.Fab")
		)
		(fp_line
			(start -3.2639 -0.1778)
			(end -2.8829 -0.1778)
			(stroke
				(width 0.1)
				(type default)
			)
			(layer "F.Fab")
		)
		(fp_line
			(start 2.8829 0.2032)
			(end 3.2639 0.2032)
			(stroke
				(width 0.1)
				(type default)
			)
			(layer "F.Fab")
		)
		(fp_line
			(start -3.6576 1.8034)
			(end -2.8956 1.8034)
			(stroke
				(width 0.1)
				(type default)
			)
			(layer "F.Fab")
		)
		(fp_line
			(start 2.500122 2.500122)
			(end -2.500122 2.500122)
			(stroke
				(width 0.1)
				(type default)
			)
			(layer "F.Fab")
		)
		(fp_line
			(start -2.500122 2.500122)
			(end -2.500122 -2.500122)
			(stroke
				(width 0.1)
				(type default)
			)
			(layer "F.Fab")
		)
		(fp_line
			(start -0.2032 2.8829)
			(end -0.2032 3.2639)
			(stroke
				(width 0.1)
				(type default)
			)
			(layer "F.Fab")
		)
		(fp_line
			(start 1.778 3.6322)
			(end 1.778 2.8702)
			(stroke
				(width 0.1)
				(type default)
			)
			(layer "F.Fab")
		)
		(fp_poly
			(pts
				(xy -2.921 -1.800098) (xy -3.504184 -1.508506) (xy -3.504184 -2.09169)
			)
			(stroke
				(width 0)
				(type default)
			)
			(fill yes)
			(layer "F.Fab")
		)
		(fp_text user "31"
			(at 0.444246 -3.39852 90)
			(unlocked yes)
			(layer "F.SilkS")
			(effects
				(font
					(size 0.635 0.4064)
					(thickness 0.1524)
				)
				(justify left)
			)
		)
		(fp_text user "30"
			(at 3.223768 -3.0988 0)
			(unlocked yes)
			(layer "F.SilkS")
			(effects
				(font
					(size 0.635 0.4064)
					(thickness 0.1524)
				)
				(justify left)
			)
		)
		(fp_text user "40"
			(at -3.2004 -3.096768 90)
			(unlocked yes)
			(layer "F.SilkS")
			(effects
				(font
					(size 0.635 0.4064)
					(thickness 0.1524)
				)
				(justify left)
			)
		)
		(fp_text user "10"
			(at -3.099562 2.1336 0)
			(unlocked yes)
			(layer "F.SilkS")
			(effects
				(font
					(size 0.635 0.4064)
					(thickness 0.1524)
				)
				(justify left)
			)
		)
		(fp_text user "21"
			(at 2.727198 2.554478 0)
			(unlocked yes)
			(layer "F.SilkS")
			(effects
				(font
					(size 0.635 0.4064)
					(thickness 0.1524)
				)
				(justify left)
			)
		)
		(fp_text user "11"
			(at -2.71653 3.278632 90)
			(unlocked yes)
			(layer "F.SilkS")
			(effects
				(font
					(size 0.635 0.4064)
					(thickness 0.1524)
				)
				(justify left)
			)
		)
		(fp_text user "20"
			(at 0.614426 3.354324 90)
			(unlocked yes)
			(layer "F.SilkS")
			(effects
				(font
					(size 0.635 0.4064)
					(thickness 0.1524)
				)
				(justify left)
			)
		)
		(fp_text user "31"
			(at 1.8542 -3.172968 90)
			(unlocked yes)
			(layer "F.Fab")
			(effects
				(font
					(size 0.635 0.4064)
					(thickness 0.1524)
				)
				(justify left)
			)
		)
		(fp_text user "30"
			(at 3.223768 -3.0988 0)
			(unlocked yes)
			(layer "F.Fab")
			(effects
				(font
					(size 0.635 0.4064)
					(thickness 0.1524)
				)
				(justify left)
			)
		)
		(fp_text user "40"
			(at -3.2004 -3.096768 90)
			(unlocked yes)
			(layer "F.Fab")
			(effects
				(font
					(size 0.635 0.4064)
					(thickness 0.1524)
				)
				(justify left)
			)
		)
		(fp_text user "21"
			(at 3.274568 1.8796 0)
			(unlocked yes)
			(layer "F.Fab")
			(effects
				(font
					(size 0.635 0.4064)
					(thickness 0.1524)
				)
				(justify left)
			)
		)
		(fp_text user "10"
			(at -3.253232 2.1336 0)
			(unlocked yes)
			(layer "F.Fab")
			(effects
				(font
					(size 0.635 0.4064)
					(thickness 0.1524)
				)
				(justify left)
			)
		)
		(fp_text user "20"
			(at 2.0828 3.253232 90)
			(unlocked yes)
			(layer "F.Fab")
			(effects
				(font
					(size 0.635 0.4064)
					(thickness 0.1524)
				)
				(justify left)
			)
		)
		(fp_text user "11"
			(at -2.8702 3.278632 90)
			(unlocked yes)
			(layer "F.Fab")
			(effects
				(font
					(size 0.635 0.4064)
					(thickness 0.1524)
				)
				(justify left)
			)
		)
		(pad "1" smd rect
			(at -2.400046 -1.800098)
			(size 0.1778 0.6096)
			(layers "F.Cu" "F.Mask" "F.Paste")
			(net "P0V8_PEX1_PWM1")
		)
		(pad "2" smd rect
			(at -2.400046 -1.400048)
			(size 0.1778 0.6096)
			(layers "F.Cu" "F.Mask" "F.Paste")
			(net "P0V8_PEX1_PWM2")
		)
		(pad "3" smd rect
			(at -2.400046 -0.999998)
			(size 0.1778 0.6096)
			(layers "F.Cu" "F.Mask" "F.Paste")
			(net "NC_P0V8_PEX0_PWM2")
		)
		(pad "4" smd rect
			(at -2.400046 -0.599948)
			(size 0.1778 0.6096)
			(layers "F.Cu" "F.Mask" "F.Paste")
			(net "NC_P0V8_PEX0_PWM3")
		)
		(pad "5" smd rect
			(at -2.400046 -0.199898)
			(size 0.1778 0.6096)
			(layers "F.Cu" "F.Mask" "F.Paste")
			(net "NC_P0V8_PEX0_PWM4")
		)
		(pad "6" smd rect
			(at -2.400046 0.199898)
			(size 0.1778 0.6096)
			(layers "F.Cu" "F.Mask" "F.Paste")
			(net "NC_P0V8_PEX0_PWM5")
		)
		(pad "7" smd rect
			(at -2.400046 0.599948)
			(size 0.1778 0.6096)
			(layers "F.Cu" "F.Mask" "F.Paste")
			(net "P0V8_PEX0_PWM2")
		)
		(pad "8" smd rect
			(at -2.400046 0.999998)
			(size 0.1778 0.6096)
			(layers "F.Cu" "F.Mask" "F.Paste")
			(net "P0V8_PEX0_PWM1")
		)
		(pad "9" smd rect
			(at -2.400046 1.400048)
			(size 0.1778 0.6096)
			(layers "F.Cu" "F.Mask" "F.Paste")
			(net "SMB_VR_P0V8_PEX0_SDA")
		)
		(pad "10" smd rect
			(at -2.400046 1.800098)
			(size 0.1778 0.6096)
			(layers "F.Cu" "F.Mask" "F.Paste")
			(net "SMB_VR_P0V8_PEX0_SCL")
		)
		(pad "11" smd rect
			(at -1.800098 2.400046 90)
			(size 0.1778 0.6096)
			(layers "F.Cu" "F.Mask" "F.Paste")
			(net "P0V8_PEX0_SMBALERT")
		)
		(pad "12" smd rect
			(at -1.400048 2.400046 90)
			(size 0.1778 0.6096)
			(layers "F.Cu" "F.Mask" "F.Paste")
			(net "P0V8_PEX0_AVRRDY")
		)
		(pad "13" smd rect
			(at -0.999998 2.400046 90)
			(size 0.1778 0.6096)
			(layers "F.Cu" "F.Mask" "F.Paste")
			(net "FM_P0V8_PEX0_EN_R")
		)
		(pad "14" smd rect
			(at -0.599948 2.400046 90)
			(size 0.1778 0.6096)
			(layers "F.Cu" "F.Mask" "F.Paste")
			(net "P0V8_PEX0_VRHOT_R")
		)
		(pad "15" smd rect
			(at -0.199898 2.400046 90)
			(size 0.1778 0.6096)
			(layers "F.Cu" "F.Mask" "F.Paste")
			(net "P0V8_PEX0_PINALRT")
		)
		(pad "16" smd rect
			(at 0.199898 2.400046 90)
			(size 0.1778 0.6096)
			(layers "F.Cu" "F.Mask" "F.Paste")
			(net "P0V8_PEX1_BVRRDY")
		)
		(pad "17" smd rect
			(at 0.599948 2.400046 90)
			(size 0.1778 0.6096)
			(layers "F.Cu" "F.Mask" "F.Paste")
			(net "P0V8_PEX0_SVID")
		)
		(pad "18" smd rect
			(at 0.999998 2.400046 90)
			(size 0.1778 0.6096)
			(layers "F.Cu" "F.Mask" "F.Paste")
			(net "P0V8_PEX0_SVID")
		)
		(pad "19" smd rect
			(at 1.400048 2.400046 90)
			(size 0.1778 0.6096)
			(layers "F.Cu" "F.Mask" "F.Paste")
			(net "NC_P0V8_PEX0_SVID_ALERT_N_R")
		)
		(pad "20" smd rect
			(at 1.800098 2.400046 90)
			(size 0.1778 0.6096)
			(layers "F.Cu" "F.Mask" "F.Paste")
			(net "FM_P0V8_PEX1_EN_R")
		)
		(pad "21" smd rect
			(at 2.400046 1.800098)
			(size 0.1778 0.6096)
			(layers "F.Cu" "F.Mask" "F.Paste")
			(net "P0V8_PEX0_VSEN0")
		)
		(pad "22" smd rect
			(at 2.400046 1.400048)
			(size 0.1778 0.6096)
			(layers "F.Cu" "F.Mask" "F.Paste")
			(net "SH_P0V8_PEX0_RGND0")
		)
		(pad "23" smd rect
			(at 2.400046 0.999998)
			(size 0.1778 0.6096)
			(layers "F.Cu" "F.Mask" "F.Paste")
			(net "P0V8_PEX0_ISEN1")
		)
		(pad "24" smd rect
			(at 2.400046 0.599948)
			(size 0.1778 0.6096)
			(layers "F.Cu" "F.Mask" "F.Paste")
			(net "P0V8_PEX0_ISEN2")
		)
		(pad "25" smd rect
			(at 2.400046 0.199898)
			(size 0.1778 0.6096)
			(layers "F.Cu" "F.Mask" "F.Paste")
			(net "NC_P0V8_PEX0_ISEN5")
		)
		(pad "26" smd rect
			(at 2.400046 -0.199898)
			(size 0.1778 0.6096)
			(layers "F.Cu" "F.Mask" "F.Paste")
			(net "NC_P0V8_PEX0_ISEN4")
		)
		(pad "27" smd rect
			(at 2.400046 -0.599948)
			(size 0.1778 0.6096)
			(layers "F.Cu" "F.Mask" "F.Paste")
			(net "NC_P0V8_PEX0_ISEN3")
		)
		(pad "28" smd rect
			(at 2.400046 -0.999998)
			(size 0.1778 0.6096)
			(layers "F.Cu" "F.Mask" "F.Paste")
			(net "NC_P0V8_PEX0_ISEN2")
		)
		(pad "29" smd rect
			(at 2.400046 -1.400048)
			(size 0.1778 0.6096)
			(layers "F.Cu" "F.Mask" "F.Paste")
			(net "P0V8_PEX1_ISEN2")
		)
		(pad "30" smd rect
			(at 2.400046 -1.800098)
			(size 0.1778 0.6096)
			(layers "F.Cu" "F.Mask" "F.Paste")
			(net "P0V8_PEX1_ISEN1")
		)
		(pad "31" smd rect
			(at 1.800098 -2.400046 90)
			(size 0.1778 0.6096)
			(layers "F.Cu" "F.Mask" "F.Paste")
			(net "SH_P0V8_PEX1_RGND1")
		)
		(pad "32" smd rect
			(at 1.400048 -2.400046 90)
			(size 0.1778 0.6096)
			(layers "F.Cu" "F.Mask" "F.Paste")
			(net "P0V8_PEX1_VSEN1")
		)
		(pad "33" smd rect
			(at 0.999998 -2.400046 90)
			(size 0.1778 0.6096)
			(layers "F.Cu" "F.Mask" "F.Paste")
			(net "P0V8_PEX0_VR_CONFIG")
		)
		(pad "34" smd rect
			(at 0.599948 -2.400046 90)
			(size 0.1778 0.6096)
			(layers "F.Cu" "F.Mask" "F.Paste")
			(net "P0V8_PEX0_ADDR")
		)
		(pad "35" smd rect
			(at 0.199898 -2.400046 90)
			(size 0.1778 0.6096)
			(layers "F.Cu" "F.Mask" "F.Paste")
			(net "P0V8_PEX0_TSEN_R")
		)
		(pad "36" smd rect
			(at -0.199898 -2.400046 90)
			(size 0.1778 0.6096)
			(layers "F.Cu" "F.Mask" "F.Paste")
			(net "P0V8_PEX1_TSEN_R")
		)
		(pad "37" smd rect
			(at -0.599948 -2.400046 90)
			(size 0.1778 0.6096)
			(layers "F.Cu" "F.Mask" "F.Paste")
			(net "P0V8_PEX0_IINSEN")
		)
		(pad "38" smd rect
			(at -0.999998 -2.400046 90)
			(size 0.1778 0.6096)
			(layers "F.Cu" "F.Mask" "F.Paste")
			(net "P0V8_PEX0_VINSEN")
		)
		(pad "39" smd rect
			(at -1.400048 -2.400046 90)
			(size 0.1778 0.6096)
			(layers "F.Cu" "F.Mask" "F.Paste")
			(net "P0V8_PEX0_VDD")
		)
		(pad "40" smd rect
			(at -1.800098 -2.400046 90)
			(size 0.1778 0.6096)
			(layers "F.Cu" "F.Mask" "F.Paste")
			(net "P0V8_PEX0_VREF")
		)
		(pad "TH" smd rect
			(at 0 0 90)
			(size 3.6576 3.6576)
			(layers "F.Cu" "F.Mask" "F.Paste")
			(net "GND")
		)
		(zone
			(layer "F.Cu")
			(hatch none 0.5)
			(connect_pads
				(clearance 0)
			)
			(min_thickness 0.25)
			(keepout
				(tracks not_allowed)
				(vias allowed)
				(pads allowed)
				(copperpour not_allowed)
				(footprints allowed)
			)
			(placement
				(enabled no)
				(sheetname "")
			)
			(fill
				(thermal_gap 0.5)
				(thermal_bridge_width 0.5)
				(island_removal_mode 0)
			)
			(polygon
				(pts
					(xy 118.74373 -256.362962) (xy 118.74373 -260.426962) (xy 122.80773 -260.426962) (xy 122.80773 -256.362962)
					(xy 118.92153 -256.362962) (xy 118.92153 -256.515362) (xy 122.65533 -256.515362) (xy 122.65533 -260.274562)
					(xy 118.89613 -260.274562) (xy 118.89613 -256.362962)
				)
			)
		)
	)
	(footprint ""
		(layer "F.Cu")
		(at 428.754794 -22.961346 90)
		(property "Reference" "R1729"
			(at 0 0 90)
			(layer "F.SilkS")
			(hide yes)
			(effects
				(font
					(size 1.27 1.27)
				)
			)
		)
		(property "Value" ""
			(at 0 0 90)
			(layer "F.Fab")
			(effects
				(font
					(size 1.27 1.27)
				)
			)
		)
		(duplicate_pad_numbers_are_jumpers no)
		(fp_line
			(start 0.7874 -0.4064)
			(end 0.7874 0.4064)
			(stroke
				(width 0.1524)
				(type default)
			)
			(layer "F.SilkS")
		)
		(fp_line
			(start -0.7874 -0.4064)
			(end 0.7874 -0.4064)
			(stroke
				(width 0.1524)
				(type default)
			)
			(layer "F.SilkS")
		)
		(fp_line
			(start 0.7874 0.4064)
			(end -0.7874 0.4064)
			(stroke
				(width 0.1524)
				(type default)
			)
			(layer "F.SilkS")
		)
		(fp_line
			(start -0.7874 0.4064)
			(end -0.7874 -0.4064)
			(stroke
				(width 0.1524)
				(type default)
			)
			(layer "F.SilkS")
		)
		(fp_line
			(start -0.12065 -0.305054)
			(end -0.12065 -0.2794)
			(stroke
				(width 0.1)
				(type default)
			)
			(layer "F.Fab")
		)
		(fp_line
			(start -0.67945 -0.305054)
			(end -0.12065 -0.305054)
			(stroke
				(width 0.1)
				(type default)
			)
			(layer "F.Fab")
		)
		(fp_line
			(start 0.67945 -0.3048)
			(end 0.67945 0.3048)
			(stroke
				(width 0.1)
				(type default)
			)
			(layer "F.Fab")
		)
		(fp_line
			(start 0.12065 -0.3048)
			(end 0.67945 -0.3048)
			(stroke
				(width 0.1)
				(type default)
			)
			(layer "F.Fab")
		)
		(fp_line
			(start 0.12065 -0.2794)
			(end 0.12065 -0.3048)
			(stroke
				(width 0.1)
				(type default)
			)
			(layer "F.Fab")
		)
		(fp_line
			(start -0.12065 -0.2794)
			(end 0.12065 -0.2794)
			(stroke
				(width 0.1)
				(type default)
			)
			(layer "F.Fab")
		)
		(fp_line
			(start 0.120396 0.2794)
			(end -0.12065 0.2794)
			(stroke
				(width 0.1)
				(type default)
			)
			(layer "F.Fab")
		)
		(fp_line
			(start -0.12065 0.2794)
			(end -0.12065 0.3048)
			(stroke
				(width 0.1)
				(type default)
			)
			(layer "F.Fab")
		)
		(fp_line
			(start 0.67945 0.3048)
			(end 0.120396 0.3048)
			(stroke
				(width 0.1)
				(type default)
			)
			(layer "F.Fab")
		)
		(fp_line
			(start 0.120396 0.3048)
			(end 0.120396 0.2794)
			(stroke
				(width 0.1)
				(type default)
			)
			(layer "F.Fab")
		)
		(fp_line
			(start -0.12065 0.3048)
			(end -0.67945 0.3048)
			(stroke
				(width 0.1)
				(type default)
			)
			(layer "F.Fab")
		)
		(fp_line
			(start -0.67945 0.3048)
			(end -0.67945 -0.305054)
			(stroke
				(width 0.1)
				(type default)
			)
			(layer "F.Fab")
		)
		(pad "1" smd circle
			(at -0.40005 0 90)
			(size 0 0)
			(layers "F.Cu" "F.Mask" "F.Paste")
			(net "SMB_SSD14_ISO_EN")
		)
		(pad "2" smd circle
			(at 0.40005 0 90)
			(size 0 0)
			(layers "F.Cu" "F.Mask" "F.Paste")
			(net "P3V3_AUX")
		)
	)
)
